(kicad_pcb
	(version 20260206)
	(generator "pcbnew")
	(generator_version "10.0")
	(general
		(thickness 1.6)
		(legacy_teardrops no)
	)
	(paper "A4")
	(title_block
		(title "01162023_DA0F0TEBIF0_F0T_Expander_BD_F_brd_V02_OCP.brd")
		(comment 1 "Grand Teton / footprints 2124-2129 of 9728")
	)
	(layers
		(0 "F.Cu" signal "TOP")
		(4 "In1.Cu" signal "GND")
		(6 "In2.Cu" signal "VCC")
		(8 "In3.Cu" signal "VCC1")
		(10 "In4.Cu" signal "GND1")
		(12 "In5.Cu" signal "IN1")
		(14 "In6.Cu" signal "GND2")
		(16 "In7.Cu" signal "IN2")
		(18 "In8.Cu" signal "GND3")
		(20 "In9.Cu" signal "IN3")
		(22 "In10.Cu" signal "GND4")
		(24 "In11.Cu" signal "IN4")
		(26 "In12.Cu" signal "GND5")
		(28 "In13.Cu" signal "IN5")
		(30 "In14.Cu" signal "GND6")
		(32 "In15.Cu" signal "IN6")
		(34 "In16.Cu" signal "GND7")
		(2 "B.Cu" signal "BOTTOM")
		(9 "F.Adhes" user "F.Adhesive")
		(11 "B.Adhes" user "B.Adhesive")
		(13 "F.Paste" user "Package Geometry/Pastemask Top")
		(15 "B.Paste" user "Package Geometry/Pastemask Bottom")
		(5 "F.SilkS" user "Ref Des/Silkscreen Top")
		(7 "B.SilkS" user "Ref Des/Silkscreen Bottom")
		(1 "F.Mask" user "Board Geometry/Soldermask Top")
		(3 "B.Mask" user "Board Geometry/Soldermask Bottom")
		(17 "Dwgs.User" user "User.Drawings")
		(19 "Cmts.User" user "User.Comments")
		(21 "Eco1.User" user "User.Eco1")
		(23 "Eco2.User" user "User.Eco2")
		(25 "Edge.Cuts" user "Board Geometry/Outline")
		(27 "Margin" user)
		(31 "F.CrtYd" user "Package Geometry/Place Bound Top")
		(29 "B.CrtYd" user "Package Geometry/Place Bound Bottom")
		(35 "F.Fab" user "Ref Des/Assembly Top")
		(33 "B.Fab" user "Ref Des/Assembly Bottom")
	)
	(footprint ""
		(layer "F.Cu")
		(at 245.203726 -306.386992 -90)
		(property "Reference" "PC261"
			(at 0 0 270)
			(layer "F.SilkS")
			(hide yes)
			(effects
				(font
					(size 1.27 1.27)
				)
			)
		)
		(property "Value" ""
			(at 0 0 270)
			(layer "F.Fab")
			(effects
				(font
					(size 1.27 1.27)
				)
			)
		)
		(duplicate_pad_numbers_are_jumpers no)
		(fp_line
			(start -0.7874 0.4064)
			(end -0.7874 -0.4064)
			(stroke
				(width 0.1524)
				(type default)
			)
			(layer "F.SilkS")
		)
		(fp_line
			(start 0.7874 0.4064)
			(end -0.7874 0.4064)
			(stroke
				(width 0.1524)
				(type default)
			)
			(layer "F.SilkS")
		)
		(fp_line
			(start -0.7874 -0.4064)
			(end 0.7874 -0.4064)
			(stroke
				(width 0.1524)
				(type default)
			)
			(layer "F.SilkS")
		)
		(fp_line
			(start 0.7874 -0.4064)
			(end 0.7874 0.4064)
			(stroke
				(width 0.1524)
				(type default)
			)
			(layer "F.SilkS")
		)
		(fp_line
			(start -0.67945 0.3048)
			(end -0.67945 -0.305054)
			(stroke
				(width 0.1)
				(type default)
			)
			(layer "F.Fab")
		)
		(fp_line
			(start -0.12065 0.3048)
			(end -0.67945 0.3048)
			(stroke
				(width 0.1)
				(type default)
			)
			(layer "F.Fab")
		)
		(fp_line
			(start 0.120396 0.3048)
			(end 0.120396 0.2794)
			(stroke
				(width 0.1)
				(type default)
			)
			(layer "F.Fab")
		)
		(fp_line
			(start 0.67945 0.3048)
			(end 0.120396 0.3048)
			(stroke
				(width 0.1)
				(type default)
			)
			(layer "F.Fab")
		)
		(fp_line
			(start -0.12065 0.2794)
			(end -0.12065 0.3048)
			(stroke
				(width 0.1)
				(type default)
			)
			(layer "F.Fab")
		)
		(fp_line
			(start 0.120396 0.2794)
			(end -0.12065 0.2794)
			(stroke
				(width 0.1)
				(type default)
			)
			(layer "F.Fab")
		)
		(fp_line
			(start -0.12065 -0.2794)
			(end 0.12065 -0.2794)
			(stroke
				(width 0.1)
				(type default)
			)
			(layer "F.Fab")
		)
		(fp_line
			(start 0.12065 -0.2794)
			(end 0.12065 -0.3048)
			(stroke
				(width 0.1)
				(type default)
			)
			(layer "F.Fab")
		)
		(fp_line
			(start 0.12065 -0.3048)
			(end 0.67945 -0.3048)
			(stroke
				(width 0.1)
				(type default)
			)
			(layer "F.Fab")
		)
		(fp_line
			(start 0.67945 -0.3048)
			(end 0.67945 0.3048)
			(stroke
				(width 0.1)
				(type default)
			)
			(layer "F.Fab")
		)
		(fp_line
			(start -0.67945 -0.305054)
			(end -0.12065 -0.305054)
			(stroke
				(width 0.1)
				(type default)
			)
			(layer "F.Fab")
		)
		(fp_line
			(start -0.12065 -0.305054)
			(end -0.12065 -0.2794)
			(stroke
				(width 0.1)
				(type default)
			)
			(layer "F.Fab")
		)
		(pad "1" smd circle
			(at -0.40005 0 270)
			(size 0 0)
			(layers "F.Cu" "F.Mask" "F.Paste")
			(net "P1V25_PEX2_REF")
		)
		(pad "2" smd circle
			(at 0.40005 0 270)
			(size 0 0)
			(layers "F.Cu" "F.Mask" "F.Paste")
			(net "GND")
		)
	)
	(footprint ""
		(layer "F.Cu")
		(at 340.561422 -189.40145 180)
		(property "Reference" "R4242"
			(at 0 0 180)
			(layer "F.SilkS")
			(hide yes)
			(effects
				(font
					(size 1.27 1.27)
				)
			)
		)
		(property "Value" ""
			(at 0 0 180)
			(layer "F.Fab")
			(effects
				(font
					(size 1.27 1.27)
				)
			)
		)
		(duplicate_pad_numbers_are_jumpers no)
		(fp_line
			(start 0.7874 0.4064)
			(end -0.7874 0.4064)
			(stroke
				(width 0.1524)
				(type default)
			)
			(layer "F.SilkS")
		)
		(fp_line
			(start 0.7874 -0.4064)
			(end 0.7874 0.4064)
			(stroke
				(width 0.1524)
				(type default)
			)
			(layer "F.SilkS")
		)
		(fp_line
			(start -0.7874 0.4064)
			(end -0.7874 -0.4064)
			(stroke
				(width 0.1524)
				(type default)
			)
			(layer "F.SilkS")
		)
		(fp_line
			(start -0.7874 -0.4064)
			(end 0.7874 -0.4064)
			(stroke
				(width 0.1524)
				(type default)
			)
			(layer "F.SilkS")
		)
		(fp_line
			(start 0.67945 0.3048)
			(end 0.120396 0.3048)
			(stroke
				(width 0.1)
				(type default)
			)
			(layer "F.Fab")
		)
		(fp_line
			(start 0.67945 -0.3048)
			(end 0.67945 0.3048)
			(stroke
				(width 0.1)
				(type default)
			)
			(layer "F.Fab")
		)
		(fp_line
			(start 0.12065 -0.2794)
			(end 0.12065 -0.3048)
			(stroke
				(width 0.1)
				(type default)
			)
			(layer "F.Fab")
		)
		(fp_line
			(start 0.12065 -0.3048)
			(end 0.67945 -0.3048)
			(stroke
				(width 0.1)
				(type default)
			)
			(layer "F.Fab")
		)
		(fp_line
			(start 0.120396 0.3048)
			(end 0.120396 0.2794)
			(stroke
				(width 0.1)
				(type default)
			)
			(layer "F.Fab")
		)
		(fp_line
			(start 0.120396 0.2794)
			(end -0.12065 0.2794)
			(stroke
				(width 0.1)
				(type default)
			)
			(layer "F.Fab")
		)
		(fp_line
			(start -0.12065 0.3048)
			(end -0.67945 0.3048)
			(stroke
				(width 0.1)
				(type default)
			)
			(layer "F.Fab")
		)
		(fp_line
			(start -0.12065 0.2794)
			(end -0.12065 0.3048)
			(stroke
				(width 0.1)
				(type default)
			)
			(layer "F.Fab")
		)
		(fp_line
			(start -0.12065 -0.2794)
			(end 0.12065 -0.2794)
			(stroke
				(width 0.1)
				(type default)
			)
			(layer "F.Fab")
		)
		(fp_line
			(start -0.12065 -0.305054)
			(end -0.12065 -0.2794)
			(stroke
				(width 0.1)
				(type default)
			)
			(layer "F.Fab")
		)
		(fp_line
			(start -0.67945 0.3048)
			(end -0.67945 -0.305054)
			(stroke
				(width 0.1)
				(type default)
			)
			(layer "F.Fab")
		)
		(fp_line
			(start -0.67945 -0.305054)
			(end -0.12065 -0.305054)
			(stroke
				(width 0.1)
				(type default)
			)
			(layer "F.Fab")
		)
		(pad "1" smd circle
			(at -0.40005 0 180)
			(size 0 0)
			(layers "F.Cu" "F.Mask" "F.Paste")
			(net "P3V3_AUX")
		)
		(pad "2" smd circle
			(at 0.40005 0 180)
			(size 0 0)
			(layers "F.Cu" "F.Mask" "F.Paste")
			(net "PWRGD_SYS_PWROK")
		)
	)
	(footprint ""
		(layer "F.Cu")
		(at 383.159 -201.168)
		(property "Reference" "R4684"
			(at 0 0 0)
			(layer "F.SilkS")
			(hide yes)
			(effects
				(font
					(size 1.27 1.27)
				)
			)
		)
		(property "Value" ""
			(at 0 0 0)
			(layer "F.Fab")
			(effects
				(font
					(size 1.27 1.27)
				)
			)
		)
		(duplicate_pad_numbers_are_jumpers no)
		(fp_line
			(start -0.7874 -0.4064)
			(end 0.7874 -0.4064)
			(stroke
				(width 0.1524)
				(type default)
			)
			(layer "F.SilkS")
		)
		(fp_line
			(start -0.7874 0.4064)
			(end -0.7874 -0.4064)
			(stroke
				(width 0.1524)
				(type default)
			)
			(layer "F.SilkS")
		)
		(fp_line
			(start 0.7874 -0.4064)
			(end 0.7874 0.4064)
			(stroke
				(width 0.1524)
				(type default)
			)
			(layer "F.SilkS")
		)
		(fp_line
			(start 0.7874 0.4064)
			(end -0.7874 0.4064)
			(stroke
				(width 0.1524)
				(type default)
			)
			(layer "F.SilkS")
		)
		(fp_line
			(start -0.67945 -0.305054)
			(end -0.12065 -0.305054)
			(stroke
				(width 0.1)
				(type default)
			)
			(layer "F.Fab")
		)
		(fp_line
			(start -0.67945 0.3048)
			(end -0.67945 -0.305054)
			(stroke
				(width 0.1)
				(type default)
			)
			(layer "F.Fab")
		)
		(fp_line
			(start -0.12065 -0.305054)
			(end -0.12065 -0.2794)
			(stroke
				(width 0.1)
				(type default)
			)
			(layer "F.Fab")
		)
		(fp_line
			(start -0.12065 -0.2794)
			(end 0.12065 -0.2794)
			(stroke
				(width 0.1)
				(type default)
			)
			(layer "F.Fab")
		)
		(fp_line
			(start -0.12065 0.2794)
			(end -0.12065 0.3048)
			(stroke
				(width 0.1)
				(type default)
			)
			(layer "F.Fab")
		)
		(fp_line
			(start -0.12065 0.3048)
			(end -0.67945 0.3048)
			(stroke
				(width 0.1)
				(type default)
			)
			(layer "F.Fab")
		)
		(fp_line
			(start 0.120396 0.2794)
			(end -0.12065 0.2794)
			(stroke
				(width 0.1)
				(type default)
			)
			(layer "F.Fab")
		)
		(fp_line
			(start 0.120396 0.3048)
			(end 0.120396 0.2794)
			(stroke
				(width 0.1)
				(type default)
			)
			(layer "F.Fab")
		)
		(fp_line
			(start 0.12065 -0.3048)
			(end 0.67945 -0.3048)
			(stroke
				(width 0.1)
				(type default)
			)
			(layer "F.Fab")
		)
		(fp_line
			(start 0.12065 -0.2794)
			(end 0.12065 -0.3048)
			(stroke
				(width 0.1)
				(type default)
			)
			(layer "F.Fab")
		)
		(fp_line
			(start 0.67945 -0.3048)
			(end 0.67945 0.3048)
			(stroke
				(width 0.1)
				(type default)
			)
			(layer "F.Fab")
		)
		(fp_line
			(start 0.67945 0.3048)
			(end 0.120396 0.3048)
			(stroke
				(width 0.1)
				(type default)
			)
			(layer "F.Fab")
		)
		(pad "1" smd circle
			(at -0.40005 0)
			(size 0 0)
			(layers "F.Cu" "F.Mask" "F.Paste")
			(net "PCA9555_0_PEX1_A0")
		)
		(pad "2" smd circle
			(at 0.40005 0)
			(size 0 0)
			(layers "F.Cu" "F.Mask" "F.Paste")
			(net "P3V3_AUX")
		)
	)
	(footprint ""
		(layer "F.Cu")
		(at 26.930096 -287.604708 -90)
		(property "Reference" "C3051"
			(at 0 0 270)
			(layer "F.SilkS")
			(hide yes)
			(effects
				(font
					(size 1.27 1.27)
				)
			)
		)
		(property "Value" ""
			(at 0 0 270)
			(layer "F.Fab")
			(effects
				(font
					(size 1.27 1.27)
				)
			)
		)
		(duplicate_pad_numbers_are_jumpers no)
		(fp_line
			(start -1.2954 0.5842)
			(end -1.2954 -0.5842)
			(stroke
				(width 0.1524)
				(type default)
			)
			(layer "F.SilkS")
		)
		(fp_line
			(start 1.2954 0.5842)
			(end -1.2954 0.5842)
			(stroke
				(width 0.1524)
				(type default)
			)
			(layer "F.SilkS")
		)
		(fp_line
			(start -1.2954 -0.5842)
			(end 1.2954 -0.5842)
			(stroke
				(width 0.1524)
				(type default)
			)
			(layer "F.SilkS")
		)
		(fp_line
			(start 1.2954 -0.5842)
			(end 1.2954 0.5842)
			(stroke
				(width 0.1524)
				(type default)
			)
			(layer "F.SilkS")
		)
		(fp_line
			(start -0.8636 0.4572)
			(end -0.8636 0.4064)
			(stroke
				(width 0.1)
				(type default)
			)
			(layer "F.Fab")
		)
		(fp_line
			(start 0.8636 0.4572)
			(end -0.8636 0.4572)
			(stroke
				(width 0.1)
				(type default)
			)
			(layer "F.Fab")
		)
		(fp_line
			(start -1.1938 0.4064)
			(end -1.1938 -0.4064)
			(stroke
				(width 0.1)
				(type default)
			)
			(layer "F.Fab")
		)
		(fp_line
			(start -0.8636 0.4064)
			(end -1.1938 0.4064)
			(stroke
				(width 0.1)
				(type default)
			)
			(layer "F.Fab")
		)
		(fp_line
			(start 0.8636 0.4064)
			(end 0.8636 0.4572)
			(stroke
				(width 0.1)
				(type default)
			)
			(layer "F.Fab")
		)
		(fp_line
			(start 1.1938 0.4064)
			(end 0.8636 0.4064)
			(stroke
				(width 0.1)
				(type default)
			)
			(layer "F.Fab")
		)
		(fp_line
			(start -1.1938 -0.4064)
			(end -0.8636 -0.4064)
			(stroke
				(width 0.1)
				(type default)
			)
			(layer "F.Fab")
		)
		(fp_line
			(start -0.8636 -0.4064)
			(end -0.8636 -0.4572)
			(stroke
				(width 0.1)
				(type default)
			)
			(layer "F.Fab")
		)
		(fp_line
			(start 0.8636 -0.4064)
			(end 1.1938 -0.4064)
			(stroke
				(width 0.1)
				(type default)
			)
			(layer "F.Fab")
		)
		(fp_line
			(start 1.1938 -0.4064)
			(end 1.1938 0.4064)
			(stroke
				(width 0.1)
				(type default)
			)
			(layer "F.Fab")
		)
		(fp_line
			(start -0.8636 -0.4572)
			(end 0.8636 -0.4572)
			(stroke
				(width 0.1)
				(type default)
			)
			(layer "F.Fab")
		)
		(fp_line
			(start 0.8636 -0.4572)
			(end 0.8636 -0.4064)
			(stroke
				(width 0.1)
				(type default)
			)
			(layer "F.Fab")
		)
		(pad "1" smd rect
			(at -0.7366 0 180)
			(size 0.7112 0.8128)
			(layers "F.Cu" "F.Mask" "F.Paste")
			(net "P1V8_PLL0_PEX0")
		)
		(pad "2" smd rect
			(at 0.7366 0 180)
			(size 0.7112 0.8128)
			(layers "F.Cu" "F.Mask" "F.Paste")
			(net "GND")
		)
	)
	(footprint ""
		(layer "F.Cu")
		(at 382.802384 -252.356874 -90)
		(property "Reference" "R1436"
			(at 0 0 270)
			(layer "F.SilkS")
			(hide yes)
			(effects
				(font
					(size 1.27 1.27)
				)
			)
		)
		(property "Value" ""
			(at 0 0 270)
			(layer "F.Fab")
			(effects
				(font
					(size 1.27 1.27)
				)
			)
		)
		(duplicate_pad_numbers_are_jumpers no)
		(fp_line
			(start -0.7874 0.4064)
			(end -0.7874 -0.4064)
			(stroke
				(width 0.1524)
				(type default)
			)
			(layer "F.SilkS")
		)
		(fp_line
			(start 0.7874 0.4064)
			(end -0.7874 0.4064)
			(stroke
				(width 0.1524)
				(type default)
			)
			(layer "F.SilkS")
		)
		(fp_line
			(start -0.7874 -0.4064)
			(end 0.7874 -0.4064)
			(stroke
				(width 0.1524)
				(type default)
			)
			(layer "F.SilkS")
		)
		(fp_line
			(start 0.7874 -0.4064)
			(end 0.7874 0.4064)
			(stroke
				(width 0.1524)
				(type default)
			)
			(layer "F.SilkS")
		)
		(fp_line
			(start -0.67945 0.3048)
			(end -0.67945 -0.305054)
			(stroke
				(width 0.1)
				(type default)
			)
			(layer "F.Fab")
		)
		(fp_line
			(start -0.12065 0.3048)
			(end -0.67945 0.3048)
			(stroke
				(width 0.1)
				(type default)
			)
			(layer "F.Fab")
		)
		(fp_line
			(start 0.120396 0.3048)
			(end 0.120396 0.2794)
			(stroke
				(width 0.1)
				(type default)
			)
			(layer "F.Fab")
		)
		(fp_line
			(start 0.67945 0.3048)
			(end 0.120396 0.3048)
			(stroke
				(width 0.1)
				(type default)
			)
			(layer "F.Fab")
		)
		(fp_line
			(start -0.12065 0.2794)
			(end -0.12065 0.3048)
			(stroke
				(width 0.1)
				(type default)
			)
			(layer "F.Fab")
		)
		(fp_line
			(start 0.120396 0.2794)
			(end -0.12065 0.2794)
			(stroke
				(width 0.1)
				(type default)
			)
			(layer "F.Fab")
		)
		(fp_line
			(start -0.12065 -0.2794)
			(end 0.12065 -0.2794)
			(stroke
				(width 0.1)
				(type default)
			)
			(layer "F.Fab")
		)
		(fp_line
			(start 0.12065 -0.2794)
			(end 0.12065 -0.3048)
			(stroke
				(width 0.1)
				(type default)
			)
			(layer "F.Fab")
		)
		(fp_line
			(start 0.12065 -0.3048)
			(end 0.67945 -0.3048)
			(stroke
				(width 0.1)
				(type default)
			)
			(layer "F.Fab")
		)
		(fp_line
			(start 0.67945 -0.3048)
			(end 0.67945 0.3048)
			(stroke
				(width 0.1)
				(type default)
			)
			(layer "F.Fab")
		)
		(fp_line
			(start -0.67945 -0.305054)
			(end -0.12065 -0.305054)
			(stroke
				(width 0.1)
				(type default)
			)
			(layer "F.Fab")
		)
		(fp_line
			(start -0.12065 -0.305054)
			(end -0.12065 -0.2794)
			(stroke
				(width 0.1)
				(type default)
			)
			(layer "F.Fab")
		)
		(pad "1" smd circle
			(at -0.40005 0 270)
			(size 0 0)
			(layers "F.Cu" "F.Mask" "F.Paste")
			(net "GND")
		)
		(pad "2" smd circle
			(at 0.40005 0 270)
			(size 0 0)
			(layers "F.Cu" "F.Mask" "F.Paste")
			(net "PEX3_MODE_SEL11")
		)
	)
	(footprint ""
		(layer "F.Cu")
		(at 370.261134 -37.951156)
		(property "Reference" "Q229"
			(at 2.132838 -1.805686 0)
			(unlocked yes)
			(layer "F.SilkS")
			(effects
				(font
					(size 0.7874 0.5842)
					(thickness 0.1524)
				)
			)
		)
		(property "Value" ""
			(at 0 0 0)
			(layer "F.Fab")
			(effects
				(font
					(size 1.27 1.27)
				)
			)
		)
		(duplicate_pad_numbers_are_jumpers no)
		(fp_line
			(start -1.376172 -1.199896)
			(end -0.508 -1.199896)
			(stroke
				(width 0.1524)
				(type default)
			)
			(layer "F.SilkS")
		)
		(fp_line
			(start -1.376172 1.199896)
			(end -1.376172 -1.199896)
			(stroke
				(width 0.1524)
				(type default)
			)
			(layer "F.SilkS")
		)
		(fp_line
			(start -0.508 -1.199896)
			(end 0 -0.762)
			(stroke
				(width 0.1524)
				(type default)
			)
			(layer "F.SilkS")
		)
		(fp_line
			(start 0 -0.762)
			(end 0.508 -1.199896)
			(stroke
				(width 0.1524)
				(type default)
			)
			(layer "F.SilkS")
		)
		(fp_line
			(start 0.508 -1.199896)
			(end 1.376172 -1.199896)
			(stroke
				(width 0.1524)
				(type default)
			)
			(layer "F.SilkS")
		)
		(fp_line
			(start 1.376172 -1.199896)
			(end 1.376172 1.199896)
			(stroke
				(width 0.1524)
				(type default)
			)
			(layer "F.SilkS")
		)
		(fp_line
			(start 1.376172 1.199896)
			(end -1.376172 1.199896)
			(stroke
				(width 0.1524)
				(type default)
			)
			(layer "F.SilkS")
		)
		(fp_poly
			(pts
				(xy -1.461262 -1.05156) (xy -1.730756 -1.859788) (xy -2.26949 -1.321054)
			)
			(stroke
				(width 0)
				(type default)
			)
			(fill yes)
			(layer "F.SilkS")
		)
		(fp_line
			(start -0.674878 -1.100074)
			(end 0.674878 -1.100074)
			(stroke
				(width 0.1)
				(type default)
			)
			(layer "F.Fab")
		)
		(fp_line
			(start -0.674878 1.100074)
			(end -0.674878 -1.100074)
			(stroke
				(width 0.1)
				(type default)
			)
			(layer "F.Fab")
		)
		(fp_line
			(start 0.674878 -1.100074)
			(end 0.674878 1.100074)
			(stroke
				(width 0.1)
				(type default)
			)
			(layer "F.Fab")
		)
		(fp_line
			(start 0.674878 1.100074)
			(end -0.674878 1.100074)
			(stroke
				(width 0.1)
				(type default)
			)
			(layer "F.Fab")
		)
		(fp_poly
			(pts
				(xy -1.4605 -0.7493) (xy -2.2225 -1.1303) (xy -2.2225 -0.3683)
			)
			(stroke
				(width 0)
				(type default)
			)
			(fill yes)
			(layer "F.Fab")
		)
		(pad "1" smd rect
			(at -0.899922 -0.750062 270)
			(size 0.6096 0.6096)
			(layers "F.Cu" "F.Mask" "F.Paste")
			(net "GND")
		)
		(pad "2" smd rect
			(at -0.899922 0 270)
			(size 0.4064 0.6096)
			(layers "F.Cu" "F.Mask" "F.Paste")
			(net "P3V3_SSD13_PG_G1")
		)
		(pad "3" smd rect
			(at -0.899922 0.750062 270)
			(size 0.6096 0.6096)
			(layers "F.Cu" "F.Mask" "F.Paste")
			(net "PWRGD_P3V3_SSD13_D")
		)
		(pad "4" smd rect
			(at 0.899922 0.750062 270)
			(size 0.6096 0.6096)
			(layers "F.Cu" "F.Mask" "F.Paste")
			(net "GND")
		)
		(pad "5" smd rect
			(at 0.899922 0 270)
			(size 0.4064 0.6096)
			(layers "F.Cu" "F.Mask" "F.Paste")
			(net "P3V3_SSD13_PG_G2")
		)
		(pad "6" smd rect
			(at 0.899922 -0.750062 270)
			(size 0.6096 0.6096)
			(layers "F.Cu" "F.Mask" "F.Paste")
			(net "P3V3_SSD13_PG_G2")
		)
	)
)
